M48
INCH,TZ
T01C.008
T02C.01
T03C.012
T04C.014
T05C.01417
T06C.016
T07C.028
T08C.035
T09C.04
T10C.138
T11C.158
T12C.168
T13C.032
T14C.034
T15C.044
T16C.048
T17C.063
T18C.086
T19C.094
T20C.097
T21C.13
;LEADER: 12 
;HEADER: 
;CODE  : ASCII 
;FILE  : 16342-2-1-8.drl for board 16342-2.brd ... layers TOP and BOTTOM
;T01 Holesize 1. = 8.000000 Tolerance = +0.000000/-0.000000 PLATED MILS Quantity = 273
;T02 Holesize 2. = 10.000000 Tolerance = +0.000000/-0.000000 PLATED MILS Quantity = 1377
;T03 Holesize 3. = 12.000000 Tolerance = +0.000000/-0.000000 PLATED MILS Quantity = 101
;T04 Holesize 4. = 14.000000 Tolerance = +0.000000/-0.000000 PLATED MILS Quantity = 8
;T05 Holesize 5. = 14.170000 Tolerance = +0.000000/-0.000000 PLATED MILS Quantity = 200
;T06 Holesize 6. = 16.000000 Tolerance = +0.000000/-0.000000 PLATED MILS Quantity = 1270
;T07 Holesize 7. = 28.000000 Tolerance = +0.000000/-0.000000 PLATED MILS Quantity = 9
;T08 Holesize 8. = 35.000000 Tolerance = +0.000000/-0.000000 PLATED MILS Quantity = 3
;T09 Holesize 9. = 40.000000 Tolerance = +0.000000/-0.000000 PLATED MILS Quantity = 8
;T10 Holesize 10. = 138.000000 Tolerance = +0.000000/-0.000000 PLATED MILS Quantity = 11
;T11 Holesize 11. = 158.000000 Tolerance = +0.000000/-0.000000 PLATED MILS Quantity = 2
;T12 Holesize 12. = 168.000000 Tolerance = +0.000000/-0.000000 PLATED MILS Quantity = 1
;T13 Holesize 13. = 32.000000 Tolerance = +0.000000/-0.000000 NON_PLATED MILS Quantity = 2
;T14 Holesize 14. = 34.000000 Tolerance = +0.000000/-0.000000 NON_PLATED MILS Quantity = 1
;T15 Holesize 15. = 44.000000 Tolerance = +0.000000/-0.000000 NON_PLATED MILS Quantity = 2
;T16 Holesize 16. = 48.000000 Tolerance = +0.000000/-0.000000 NON_PLATED MILS Quantity = 1
;T17 Holesize 17. = 63.000000 Tolerance = +0.000000/-0.000000 NON_PLATED MILS Quantity = 2
;T18 Holesize 18. = 86.000000 Tolerance = +0.000000/-0.000000 NON_PLATED MILS Quantity = 7
;T19 Holesize 19. = 94.000000 Tolerance = +0.000000/-0.000000 NON_PLATED MILS Quantity = 1
;T20 Holesize 20. = 97.000000 Tolerance = +0.000000/-0.000000 NON_PLATED MILS Quantity = 1
;T21 Holesize 21. = 130.000000 Tolerance = +0.000000/-0.000000 NON_PLATED MILS Quantity = 2
%
G90
T01
X153149Y536221
X153150Y539371
X156300
X156299Y542521
X153149
X159449
Y545671
X156299
X159449Y548821
X159412Y552006
X159449Y555118
X156297Y558267
X159449Y561417
Y567717
Y570866
X156299
X159449Y577165
X156299
X159449Y580315
X156299
Y586614
X159449
X159448Y589764
Y592913
Y596063
Y599213
X153149Y605513
X165748Y599213
X162598
X168898
Y596063
X162598
X165748
Y592913
X168898
Y589764
X165748
X162598
X165748Y586614
X162598
X168898
X165748Y583464
X168898
X162598
Y580315
X168898
X165748
X162598Y577165
X168898
X165748Y570866
X162598
X168898
X165748Y567717
X168898
X162598
X168895Y564567
X165745
X162595
X168898Y561417
X165748
X162598
Y558268
X165748
X168898
X165748Y555118
X168898Y555119
Y551969
X162599Y551970
X165748Y551968
X165749Y548819
X168898
X162599Y548821
X168898Y545669
X165749
X162599
X165777Y542555
X168898Y542519
X162599
X171906Y534661
X172047Y545669
X178346Y545670
X175197Y545671
Y548821
X172047Y548819
X178347Y551970
X172047
X175197
X178346Y555119
X172048Y555120
X175196Y558269
X172047Y561417
X178347Y564569
X172047Y564568
Y567717
X178347Y570769
X172047Y570867
X178347Y574018
X172020Y577050
X178344Y577166
X175298Y577266
X178346Y586615
X172048Y589764
X178347
X175196
X175197Y592913
X172048
X178346Y596064
X175197Y596063
X172048
X178347Y599213
X172048
X175197
X187795Y602363
X187796Y599212
X181586Y599123
X181500Y595900
X187795Y592914
X181530Y592765
X187900Y589800
X181497Y589764
X187794Y586614
X181497
X187795Y577166
X184646
X184645Y574166
X187844Y574065
X184646Y570867
X184695Y567666
X187746Y567669
X187925Y564617
X187795Y555120
X184646
X181497
X187885Y552058
X181497Y551970
Y548821
X184646
Y545671
X181497
X181496Y542520
X184645Y542519
Y539370
X194094
X197243Y539371
X197244Y542519
X194094
Y545669
X190945
X197244
X194094Y548820
X194093Y551970
X197243
X194093Y555120
X197245Y555118
X194093Y564569
X190944
X194093Y567718
X190944
X194093Y574016
X190944
X194094Y577166
X190944
X197165Y586540
X194093Y586614
X190944
Y589764
X194093
X197243Y589900
X190944Y592913
X194093
Y596063
X190944
X190945Y599213
X194094
X190944Y602362
X194094
X203605Y605821
X203543Y602362
X200393Y599212
X209841
X203542Y596063
X200393
X206692
X209841
X206692Y592913
X203450Y592912
X200393
X209841Y592913
X203542Y589764
X200393
X206692Y589763
X209842
Y586613
X206692Y586614
X203542
X200393
X206692Y583465
X209842Y583464
X206692Y580315
X203542
X209841
Y577165
X203542
X203543Y574017
X206692Y574016
X209841
X203501Y571005
X209842Y567717
X206692Y567600
Y564569
X209842Y564567
X203543Y564568
X209842Y561417
X203543Y561418
X206692Y561419
X209842Y558268
X206692Y558269
X209842Y555119
X206692Y555120
X203542
X206693Y551969
X200393Y551970
X209842Y551969
X203542Y551970
X206692Y548820
X209842Y548819
X200393
Y545669
X209842
X203542Y545671
X206692
X206693Y542520
X219291Y542519
X212991
X216141
X212992Y545669
X216142
Y548820
X219291
X212992Y548819
X216141Y551970
X212992Y551969
X216141Y555120
Y558269
Y561419
X212991
X216141Y564569
X212992Y564567
X216141Y567718
X212991
X219293Y567717
X212991Y574016
X216141
Y577165
X212991
X212992Y580315
X216141
Y583465
X212991
X212992Y586614
X216141
Y589762
X212992Y589764
X212993Y592912
X212991Y599212
X216141
X212992Y602363
X222440Y605512
X222441Y548820
X230600Y608100
X355600Y172900
X363400Y115950
X815600Y386200
T02
X28123Y453658
X29165Y532612
X29058Y538228
X29158Y543855
X28800Y549474
X28782Y555119
X28667Y634097
X56100Y676000
X41100Y671800
X50500Y667900
X50400Y663700
X37961Y659909
X42550Y599224
X58926Y582407
X42597Y571789
X53302Y567317
X37660Y566400
X53300Y560879
X33697Y560866
X52485Y555153
X52603Y549526
X52408Y543876
X52613Y538242
X53524Y532622
X34175Y526969
X53524Y526995
Y521269
X34132Y521245
X51000Y59500
X43000
X34000Y59400
X38500Y56500
X46500Y48500
X86268Y58755
X78268Y66755
X73768Y69655
X82768Y69755
X69904Y502077
X64277Y502177
X81094Y502166
X75399Y502179
X86699Y502300
X75405Y521695
X69778
X64151
X86659
X81032
X74076Y535966
X64427Y538836
X86750Y539218
X83600Y539219
X67852
X89899Y539218
X71002Y539219
X75508Y542198
X71002Y542368
X64701Y542366
X67853Y542368
X86750
X83600Y545518
X71002
X89899
X74151Y545516
X86750Y545518
X78276Y545566
X61100Y546700
X71002Y548668
X81276Y548766
X62276Y550493
X74498Y551757
X83600Y551817
X86750Y551815
X71002Y554967
X86750Y554965
X63456Y555041
X67853Y554967
X86750Y558115
X71002Y558117
X89899Y558115
X67853Y558117
X71002Y561266
X64701
X67853
X86750Y561265
X83600
X89899
X75066Y563235
X71002Y564396
X86750Y564415
X89899
X83600
X67853Y564416
X64701
X89899Y567565
X74152
X86750
X83600
X71002
X64701Y567566
Y570716
X67853Y570715
X75197Y572437
X86750Y573864
X83600Y573865
X67853
X89899Y573864
X71002Y577013
X67853Y577015
X89899Y577014
X86750
X74152Y577013
Y580163
X83601Y580164
X74152Y583312
X67852Y583313
X86750
X67852Y586463
X64703
X86750
X89901Y587466
X70700Y629000
X85400Y629784
X64884Y650984
X89868Y689124
X86028Y696439
X81928Y697539
X73427Y699285
X106355Y710745
X119849Y709715
X106879Y707245
X111300Y705500
X106635Y701465
X94106Y699683
X104550Y647050
X119000Y647000
X104850Y639150
X116400Y626600
X103098Y624364
X113400Y621400
X119900Y621000
X103098Y620264
X113400Y617400
X108137Y615870
X113512Y613401
X103098Y612064
X118900Y609900
X113426Y609234
X103109Y608572
X103124Y605153
X113672Y605134
X98537Y601094
X102509Y601100
X94011Y597066
X101608Y596523
X93051Y587466
X96570Y581730
X93048Y580164
X108371Y577258
X93048Y577014
X93049Y573864
X117400Y567650
X94720Y557158
X119605Y548705
X106272Y547370
X94473Y547093
X117200Y546300
X93744Y542019
X92600Y535623
X96371Y534124
X97913Y521695
X119400Y521700
X92286Y521695
X105350Y511850
X119400Y511500
X102601Y507300
X97926Y502300
X112722Y493971
X97074Y492891
X100600Y490750
X118197Y490300
X108500Y475500
X104000
X98400Y473200
X113300Y448564
X118065Y448535
X90768Y69755
X121233Y450900
X148490Y451286
X144245Y452344
X140985Y454250
X138023Y456188
X132777Y462639
X143700Y469000
X148000
X135262Y475726
X130787Y479138
X149000Y488600
X140490Y488605
X145000Y488600
Y497600
X125400Y498600
X120500Y504600
X141980Y508590
X135012Y510200
X146900Y512500
X148050Y523740
X138900Y525999
X144087Y526413
X133800Y528500
X143415Y530143
X123300Y530300
X136974Y534479
X123200Y534600
X133554Y537374
X127300Y543200
X130311Y546700
X126337Y554085
X122600Y557480
X130607Y569636
X126347Y569556
X148409Y575672
Y579353
X144876Y587173
Y590854
X137000Y607850
X140400
X130700
X144263Y609023
X133835Y609620
X139500Y611200
X124903Y613900
X128700Y615500
X124793Y617299
X131200Y620600
X135706Y621187
X141742Y624666
X148210Y629830
X144737Y630882
X138970Y632277
X138700Y636655
X142572Y640332
X127100Y647000
X123100
X135000Y650000
X131300Y650100
X121300Y651900
X143174Y666586
X139774Y666686
X148249Y695765
X125376Y701124
X162100Y711215
X150849Y710215
X162360Y706888
X176447Y704925
X162700Y703500
X151130Y703440
X168273Y696434
X158994Y694545
X151949Y691715
X159058Y641132
X177100Y640400
X173000
X166500Y640300
X150872Y640332
X174799Y630303
X171400Y630200
X178200Y629800
X154500Y629600
X151800Y615400
X179700Y615300
X162750Y612217
X151800Y610300
X164400Y609200
X156200Y535800
X154400Y533500
X179400Y525100
X166600Y524100
X174717Y524010
X174400Y519283
X170700Y513600
X154730Y512704
X158241Y512675
X150553Y512500
X167680Y510640
X178869Y509793
X171200Y509840
X174700Y509600
X160286Y508429
X179000Y499800
X170800
X174900
X162537Y499000
X158000
X166761Y498900
X176900Y496500
X156000Y496100
X170870Y492270
X167821Y488301
X155710Y485200
X172900Y484101
X169252Y483871
X153489Y481559
X172300Y478400
X167656Y465300
X154334Y465100
X171537Y464400
X175115Y463761
X179100Y455800
X155877Y450439
X151877
X163031Y441700
X193400Y463300
X189700Y463500
X186254Y463761
X200260Y465900
X188708Y468154
X196100Y482200
X194411Y485447
X190036Y485520
X198200Y486500
X201600
X181200Y489451
X208370Y491570
X188834Y496920
X193200Y497000
X196800Y497862
X200650
X185615Y498015
X207500Y502412
Y505812
X203350Y506700
X191398Y509000
X199501Y509275
X187100Y509600
X182964Y510414
X190929Y512592
X195200Y513200
X203500Y513500
X198700
X182870Y513832
X191200Y522500
X187500Y523700
X183750Y524200
X191300Y525900
X208700Y529100
X200200Y529200
X203610Y529397
X188600Y531500
X203696Y533000
X199950Y614000
X196100Y614050
X203900Y614100
X209193Y614249
X185100Y614300
X191210Y617900
X203300Y628900
X188899Y629597
X185500Y629700
X182100Y629800
X193400Y630600
X197611Y630698
X200100Y633300
X200963Y636600
X193400Y639700
X185300
X189500
X181000
X198700
X184807Y643963
X208200Y645500
X195600Y646000
X199600Y646300
X204100Y646500
X207000Y654400
X200000Y664200
X191766Y679920
X188500Y686800
X205827Y695000
X188600Y696800
X195500Y696900
X205800Y698400
X185598Y709274
X182200Y709400
X217638Y695562
X221575Y695400
X239000Y691000
X235100Y679921
X239400Y677600
X210123Y662100
X231500Y659100
X235042Y656173
X236000Y646100
X230270Y645933
X226708Y645869
X223013Y645672
X211706Y645349
X215606Y645300
X219200
X228900Y635800
X218800Y635600
X215800Y631200
X225900Y630988
X222500Y630200
X234000Y628400
X215400Y626800
X230063Y618667
X234087Y618038
X235800Y615100
X212923Y615000
X225900
X221800Y614800
X232896Y613795
X218200Y609500
X233447Y603747
X232300Y600300
X229800Y593200
X237100Y590000
X230900Y581600
X234700
X231200Y576800
X234800Y572000
X231000Y571900
X234943Y565199
X227600Y563000
X231450
X233607Y557671
X228313Y552169
X233850Y552201
X228100Y545500
X228800Y542100
X234648Y540453
X222500Y536161
X223800Y531600
X212300Y529000
X227100Y525400
X211700Y513500
X238600Y509900
X233100Y509800
X226357Y504514
X221960Y504230
X236400Y502150
X228200Y496200
X227100Y490300
X214900Y490000
X211324Y489886
X237903Y489800
X231400
X233664Y482859
X226475Y480400
X226500Y477000
X213900Y474650
X214808Y463300
X213159Y460326
X237600Y455500
X225532Y450047
X231476Y449662
X226607Y444058
X230610Y444055
X222995Y443805
X236400Y440800
X257950Y440600
X254100Y440800
X240900Y440900
X253400Y453500
X249465Y458000
X245874Y458478
X242500Y458900
X264800Y467400
X252626Y469150
X244300Y474150
X244400Y478600
X267670Y485870
X266664Y493000
X269100Y509063
X242600Y509800
X248459Y523892
X254494Y529198
X257894Y529254
X263400Y531500
X246508Y532821
X263600Y535350
X241154Y536017
X252400Y539600
X255800
X248700Y540000
X244850Y540150
X263600Y540700
X242700Y548600
X250445Y548551
X262996Y548757
X260900Y553900
X251346Y554100
X265100Y562300
X256816Y563982
X260513Y564135
X262694Y568076
X261300Y571300
X264200Y574100
X256007Y575050
X268200Y578700
X255400Y579500
X245400Y581800
X248800Y582000
X259848Y583194
X258596Y586356
X254408Y586483
X261900Y588900
X246800Y589600
X242333Y593800
X254043Y598359
X260705
X257346Y599169
X246500Y602500
X257332Y602569
X260850Y603537
X254208Y603995
X258398Y605915
X264358Y608152
X258398Y609484
X247088Y610236
X258600Y613100
X259000Y617000
X255663Y617763
X254821Y627000
X255228Y631071
X258873Y631373
X264800Y632300
X261810Y633980
X241300Y635900
X250400Y636976
X245100Y639500
X263500Y643212
X267500Y645600
X263800Y648902
X247725Y656375
X266400Y662200
X262826Y662274
X247825Y670375
X255050Y675750
X266550
X243100Y677500
X266398Y679250
X255000Y679900
X254600Y685100
X267045Y695881
X245971Y698400
X261900Y699300
X267100Y699700
X254900Y701950
X269003Y704337
X254700Y708900
X243731Y709100
X262645Y712155
X258431Y712169
X268820Y715100
X268520Y719420
X268230Y723570
X254648Y745463
X298570Y743670
X282353Y740020
X287220Y737920
X291700Y737000
X293075Y726600
X280600Y711700
X280500Y708100
X276400Y700650
X271240Y698960
X276400Y697250
X294804Y695204
X279400Y686400
X277600Y680200
X271220Y679910
X284000Y678300
X272900Y669100
X297118Y668882
X290600Y668200
X272300Y665700
X297900Y664800
X289473Y657061
X278150Y648363
X288720Y641455
X282620Y640950
X292400Y640500
X278150Y637250
X292400Y637000
X293600Y629100
X293500Y625600
X270300Y622315
X286700Y611911
X279745Y608000
X274800Y607500
X281500Y598419
X279214Y591383
X274100Y591000
X293697Y589566
X299100Y589200
X276783Y588907
X281636Y588796
X281510Y583003
X273022Y580751
X291839Y578193
X279450Y577970
X275652Y577455
X292006Y574797
X276376Y574132
X289070Y573080
X281975Y572963
X285400Y572556
X286400Y569200
X279800Y569182
X289800
X293970Y564927
X288000Y561000
X285833Y557629
X271715Y556690
X270021Y549394
X285800
X296254Y546706
X298719Y542538
X292200Y542473
X283600Y539294
X272100Y537500
X279200Y531600
X279600Y527900
X297850Y524500
X293500Y522600
X298200Y521100
X293600Y518400
X287500Y518000
X275100Y509800
X293800Y503300
X290000Y503200
X286061Y502378
X288311Y496200
X293326Y494174
X275276Y494017
X275700Y490300
X271100Y485900
X276591Y483709
X275113Y476513
X275100Y472400
X278800Y467500
X275300Y467300
X273400Y449700
X280600Y448900
X277455Y446150
X295700Y428400
X294720Y185600
Y182200
Y178600
X320700Y177800
X305651Y199283
X305703Y202696
X306407Y206057
X305498Y213824
X305782Y217274
X323842Y219284
X305782Y220674
X324000Y222800
X305682Y224074
X323800Y227000
X305382Y227474
X323700Y230600
X305782Y230874
X305882Y234274
X305772Y237673
X305781Y241076
X305454Y244461
X306446Y247874
X305373Y251101
X306412Y254339
X321197Y254433
X304548Y261008
Y265008
X321281Y266486
X304548Y268508
Y272508
X307567Y273592
Y277592
X321432Y279090
X307567Y281092
Y285092
X304267Y286192
Y290192
X321882Y291874
X328182Y292477
X304267Y293692
X328182Y296477
X304267Y297692
X307567Y298792
X328182Y299977
X307567Y302792
X328182Y303977
X321882Y304374
X307567Y306292
Y310292
X304267Y311392
Y315392
X321432Y316885
X328182Y317624
X304267Y318892
X328182Y321624
X304267Y322892
X307567Y323992
X328182Y325124
X307567Y327992
X328182Y329124
X321432Y329484
X307567Y331492
Y335492
X304267Y336592
Y340592
X321432Y342082
X328187Y342816
X304267Y344092
X328187Y346816
X304267Y348092
X307567Y349192
X328187Y350316
X307567Y353192
X328187Y354316
X321432Y354681
X307567Y356692
Y360692
X304267Y361792
Y365792
X320832Y367479
X328182Y368018
X304267Y369292
X328182Y372018
X304267Y373292
X328182Y375518
X320932Y377074
X328182Y379518
X303900Y380574
X321100Y384874
X321859Y388315
X324916Y435360
X328313Y435513
X321700Y436650
X323400Y507540
X326900Y507700
X311900Y511500
X305350Y514300
X327800Y514900
X311900
X313300Y518800
X309600Y520150
X318200Y522900
X301300Y524400
X322900Y530600
X327300Y540100
X312300Y540600
X302506Y543341
X327403Y543499
X307800Y546700
X302665Y547006
X327417Y548344
X305913Y549643
X302700Y551300
X329050Y552315
X304800Y554443
X307350Y561290
X304436Y564081
X315893Y567721
X304124Y570227
X315616Y571817
X315315Y575204
X317813Y580469
X324900Y581600
X302300Y582000
X317813Y584969
X303000Y586800
X307542Y588138
X325899Y589186
X325761Y592959
X307650Y596000
X325762Y596900
X323413Y602491
X317572Y603183
X300043Y603619
X303468Y603647
X321421Y605265
X305470Y623734
X303741Y654095
X328600Y661100
X304100Y666500
X300700Y667000
X314398Y670254
X317516Y671612
X315000Y674900
X318000Y678270
X328356Y678679
X327062Y697600
X328087Y701587
X316465Y716063
X306470Y743570
X337481Y719818
X342208Y714950
X334000Y714640
X352800Y702960
X332800Y691970
X342542Y685983
X332824Y684270
X342645Y682506
X338301Y673907
X330593Y671019
X353700Y670900
X338135Y670511
X340000Y662200
X336000
X347013Y656090
X343372Y655836
X329989Y653920
X355100Y651827
X336387Y648987
X351547Y645938
X348314Y643853
X332200Y643800
X359000Y635600
X341750Y630790
X341755Y627231
X353500Y624500
X341755Y623682
X342330Y620300
X344940Y617720
X341600Y616962
Y613413
X348000Y612661
X341690Y609930
X334264Y602648
X337813
X330800Y602610
X341210Y602420
X353669Y600881
X358646Y596456
X352716Y594135
Y590535
X347784Y587509
X336923Y586749
X347784Y584109
X336923Y583349
X352472Y581000
X334923Y579949
X355700Y579317
X340920Y575234
X350746Y574837
X341558Y567689
X348220Y563836
X344812Y563844
X341349Y563750
X341400Y560050
X341615Y556015
X334811Y551476
X331900Y549700
X332698Y543738
X336723Y542000
X352734Y541826
X332940Y539287
X352921Y536521
X341300Y536200
X330200Y535200
X336953Y534506
X330200Y531800
X336881Y530496
X346440Y527500
X331000Y522100
X339062Y521100
X350879Y520400
X355600Y513500
X344600Y511800
X355700Y510000
X344600Y507600
X355600Y506600
X336800Y506300
X333400Y503800
X335000Y500600
X354300Y500245
X344755Y497841
X335000Y497000
X344688Y493896
X348997Y491678
X339900Y454000
X359400Y451600
X344900Y442800
X343050Y438900
X350408Y393708
X348006Y391300
X340606Y389899
X336000Y384400
X349100Y379100
X336230Y377800
X346300Y374600
X359323Y372277
X334582Y366974
Y362974
Y359474
Y355474
Y341721
Y337721
Y334221
Y330221
X334593Y316584
Y312584
Y309084
Y305084
X334107Y291354
Y287354
Y283854
Y279854
X333882Y273978
Y270578
X333782Y267178
X334482Y263778
X334260Y255820
X334282Y252378
X334198Y248824
X335098Y233078
X335100Y228117
X354282Y191718
Y187718
X355300Y179300
X340706Y128612
X348900Y115400
X355500Y109000
X352000
X345069Y108533
X340080Y108432
X357500Y104200
X380500Y30000
X384000
X380500Y33500
X372500Y44500
X382631Y48200
X382547Y52800
X372500Y56500
X375300Y62150
Y72050
X372500Y78000
X376000Y78400
X385964Y80089
X387833Y82930
X382500Y88000
X372500Y90000
X363100Y124600
X366500Y124700
X365800Y193750
X365900Y198500
X362150Y214174
X364000Y240100
X363828Y243944
X386250Y318250
X373700Y329700
X380600Y335700
X381009Y343909
X380799Y347303
X377300Y362700
X376910Y366078
X363586Y375809
X363701Y379208
X363699Y382608
X363703Y386008
X378937Y443491
X376697Y446050
X378840Y448690
X374030Y449526
X363942Y450591
X377691Y451891
X372575Y452600
X366700Y454800
X380200Y457800
X387500Y458200
X381400Y462000
X373534Y462830
X381370Y465500
X373576Y466300
X387950Y466800
X381276Y469106
X370900Y471700
X361013Y475128
X370800
X389081Y475224
X378200Y476600
X373700Y482700
X379448Y487250
X361250Y491650
X388123Y492432
X366900Y499942
X362500Y499970
X362666Y504265
X368900Y505000
X372714Y509275
X372494Y513020
X368100Y513100
X387700Y517700
Y521600
X387800Y525500
X364000
X367500Y526800
X387800Y529400
X372900Y538700
X365730Y541050
X376617Y544817
X384400Y545195
X387400Y547500
X370763Y547900
X362801Y548097
X370800Y551300
X362280Y554590
X370800Y554700
X383080Y554897
X384347Y558647
X382922Y561735
X366490Y564360
X383126Y565162
X368399Y567372
X365953Y570753
X362250Y570875
X372951Y576851
X383411Y577024
X375700Y580102
X386224Y580524
X360980Y582586
X366500Y586300
X366100Y590000
X380572Y592095
X364300Y592900
X378400Y594800
X367133Y596067
X382600Y609000
X382380Y612620
X384500Y616500
X383313Y621780
X371180Y629236
X361227Y630300
X377714Y631280
X374252Y641029
X385700Y641300
X388338Y643600
X374200Y645871
X388338Y647149
X388418Y650549
X378832Y659705
X384466Y661650
X371457Y667593
X368060Y667743
X364600Y670800
X361914Y680181
X363664Y688950
X386050Y701200
X373060Y702960
X379100Y703300
X372100Y711700
X383600Y711800
X379450Y714400
X392079Y703434
X396306Y698732
X390355Y690926
X392100Y683900
X392000Y679800
X401000Y676500
X390500Y669200
Y665800
X398600Y662700
X396400Y659800
X390600Y625500
X394800Y609700
X396200Y597200
X396300Y587000
X396400Y583500
X394300Y576600
X395100Y572899
X395127Y568056
X393100Y564400
X393465Y553100
X394880Y548670
X396400Y545500
X393889Y543207
X397650Y536671
Y523900
Y519400
Y508250
X390651Y499000
X390769Y495379
X394952Y485300
X394700Y481700
X398000Y165400
X398050Y162000
X405100Y159300
X400000Y159200
X400924Y155896
X404473
X399900Y152100
X406400Y150300
X391382Y82930
X394070Y80840
X396800Y74800
X432269Y19980
X447233Y48829
X446788Y55180
X425765Y56265
X448000Y80404
X444800Y82404
X441100Y110950
X448996Y117666
X457000Y117800
X455766Y114535
X473600Y108300
X471281Y105681
X463479Y99412
X462874Y95922
X459500Y95500
X478590Y70310
X478700Y62800
X476100Y60500
X460300Y57600
X469000Y50100
X472800Y50000
X462372Y49179
X458041Y47341
X479040Y47134
X450454Y38147
X478426Y20427
X467016Y20430
X504900Y18200
X508646Y18386
X496242Y22287
X496355Y26000
X496394Y30000
X486700Y31100
X486400Y38500
X482727Y41870
X486527Y41939
X499721Y46102
X505633Y46932
X486535Y47449
X499623Y49524
X482397Y52176
X502300Y58200
X482200Y70500
X485700
X487500Y73400
X498500Y84200
X501100Y86800
X502379Y103194
X505779
X503700Y107600
X480538Y112071
X513379Y103325
X509981Y103194
X513300Y83000
X538456Y65144
X513500Y62000
X518890Y59730
X515500Y59000
X532500Y58600
X528300Y58648
X515785Y55552
X515700Y50899
X531050Y46998
X540800Y111500
X543059Y108958
X586754Y53967
X577847Y50807
X582447Y50607
X575300Y45967
X576649Y39585
X599254Y37967
X582797Y31807
X588647Y28007
X588753Y24080
X600847Y33907
X603747Y71407
X636647Y64300
X642998Y127863
X642574Y131843
X653634Y513757
X656846Y521702
X657199Y530195
X655092Y536171
X657921Y539000
X688672Y554572
X686198Y552098
X676327Y549874
X683369Y549269
X673498Y547045
X687292Y545486
X671024Y544571
X663224Y544303
X684818Y543012
X668195Y541742
X660395Y541474
X681989Y540183
X677756Y524511
X683661
X689567
X671850
X666800Y519500
X662400
X678740Y508760
X669749Y458022
X680200Y449500
X683000Y447200
X668531Y71500
X673647Y33107
X685907Y30622
X675903Y29541
X680000Y23900
X680300Y17500
X710550Y18550
X718300Y387700
X713200
X711300Y423800
X700900
X698651Y428165
X705450Y440950
X712000Y442100
X716100
X701183Y453339
X704836
X712874Y470182
X709700Y480332
X696070Y483486
X707391Y484208
X708367Y491000
X705700Y493500
X716536Y523519
X701378Y524511
X707283
X713189
X695472
X719394Y536305
X715000Y547027
X696624Y548249
X690121Y548315
X705853Y549017
X717829Y549856
X699453Y551078
X708682Y551846
X701927Y553552
X711156Y554320
X704756Y556381
X713985Y557149
X691501Y557401
X723132Y555159
X733985Y555249
X731156Y552420
X720303Y552330
X728682Y549946
X725853Y547117
X738779Y536435
X725000
X742716
X720536Y523519
X728036
X724036
X723800Y475164
X721100Y442100
X725200
X740500Y431000
Y426800
X725288Y405950
X723800Y18600
X766200Y22000
X777500Y34500
X777165Y509835
X762679Y535537
X776181Y536435
X770275
X765935Y537009
X759342Y543603
X753434Y545434
X756263Y548263
X765434Y549934
X758737Y550737
X775934Y550934
X768263Y552763
X761566Y553566
X778763Y553763
X770737Y555237
X773566Y558066
X793566Y560066
X803066Y559566
X784066Y559066
X790737Y557237
X809237
X800237Y556737
X781237Y556237
X788263Y554763
X806763
X797763Y554263
X803934Y551934
X785434
X794934Y551434
X809934Y545434
X805708Y536435
X799803
X793897
X787992
X782086
X803300Y491600
X806888Y491398
X807400Y477229
X799000Y441100
X804000
X794900
X808100
X783800Y422800
X794200
X809702Y416359
X808188Y404950
X801200Y386700
X796100
X820059Y331701
X835316Y340914
X830133Y353930
X815541Y354089
X830531Y361589
X816997Y371022
X822300Y390000
X811300Y395900
X821800Y400500
X821700Y403900
X822300Y418900
X831650Y422612
X811668Y433703
X820150Y433900
X823710Y469835
X811142Y470358
X825000Y536200
X817519Y536435
X811614
X837204
X837066Y543931
X839895Y546760
X812763Y548263
X822434Y550434
X815237Y550737
X825263Y553263
X818066Y553566
X827737Y555737
X830566Y558566
X812066Y560066
X845198Y552063
X842369Y549234
X841141Y536435
X855320Y414472
X856720Y409372
X849420Y407748
X861484Y399069
X847629Y391998
X842820Y382172
X847720Y371072
X864920Y368972
X861420Y367269
X842916Y357214
X846456Y350814
X850730Y350483
X868433Y349134
X841116Y348914
X857700Y222300
X860868Y219764
X848868Y219064
X858632Y216929
X864492Y206435
X851137Y199864
X845168Y192764
X864992Y175435
X867653Y172764
X843160Y169467
X854634Y166390
X842511Y164078
X867851Y163585
X840122Y156614
X858622Y155614
X854596Y155288
X842022Y152174
T03
X70800Y660700
X60800Y660900
X65700
X70600Y665800
X65714Y665850
X60700Y665900
X60600Y670900
X70700Y671000
X65900
X130019Y724095
X139916Y723822
X135019Y723595
X130019Y720495
X139916Y720222
X135019Y719095
X130019Y716895
X139916Y716622
X135019Y714845
X130019Y713295
X139916Y713022
X135019Y710595
X130019Y709695
X139916Y709422
X130019Y706095
X135019
X139916Y705822
X295820Y715220
X300620
X290520Y715120
X290620Y710120
X295634Y710070
X300520Y710020
X290720Y705120
X295620
X300720Y704920
X311286Y643750
X306486
X301186Y643650
X306300Y638600
X311186Y638550
X301286Y638650
X301386Y633650
X306286
X311386Y633450
X312289Y535181
X265400Y446100
X358800Y606300
X371400Y606400
X365300Y606500
X358864Y612620
X365164
X371400Y612700
X358900Y618800
X371300
X365500Y619000
X468000Y39500
X464000Y35500
X472000
X468000Y35400
Y31500
X603943Y42806
X608143Y42906
X603943Y47006
X608043
X706275Y445986
X753800Y535000
X864220Y386772
X857020
X860620
X875020
X867820
X871420
X867820Y383172
X871420
X860620
X864220
X875020
X857020
X867820Y379572
X875020
X857020
X860620
X871420
X864220
X864472Y196265
X860872
X878872
X875272
X871672
X868072
X869622Y191265
X873872
X865372
X878372
X860872
X868072Y186265
X878872
X864472
X860872
X871672
X875272
T04
X428740Y179528
X442913
X457086
X471260
X513779
X527953
X542126
X556299
T05
X428740Y121654
Y125985
X421653Y126378
Y130709
X428740Y131496
Y135827
X421653Y136221
X428740Y140158
X421653Y140551
Y144882
X428740Y145670
Y150000
X421653Y150394
X428740Y154331
X421653Y154725
Y159055
X428740Y159843
Y164173
X421653Y164567
X428740Y168504
X421653Y168898
Y173229
X428740Y174016
X421653Y178740
Y183071
X435827
Y178740
Y173229
Y168898
Y164567
Y159055
Y154725
Y150394
Y144882
Y140551
Y136221
Y130709
Y126378
X442913Y121654
Y125985
Y131496
Y135827
Y140158
Y145670
Y150000
Y154331
Y159843
Y164173
Y168504
Y174016
X450000Y183071
Y178740
X457086Y174016
X450000Y173229
Y168898
X457086Y168504
X450000Y164567
X457086Y164173
Y159843
X450000Y159055
Y154725
X457086Y154331
X450000Y150394
X457086Y150000
Y145670
X450000Y144882
Y140551
X457086Y140158
X450000Y136221
X457086Y135827
Y131496
X450000Y130709
Y126378
X457086Y125985
Y121654
X464173Y126378
Y130709
Y136221
Y140551
Y144882
Y150394
Y154725
Y159055
Y164567
Y168898
Y173229
Y178740
Y183071
X471260Y174016
Y168504
Y164173
Y159843
Y154331
Y150000
Y145670
Y140158
Y135827
Y131496
Y125985
Y121654
X506693Y126378
Y130709
Y136221
Y140551
Y144882
Y150394
Y154725
Y159055
Y164567
Y168898
Y173229
Y178740
Y183071
X513779Y174016
Y168504
Y164173
Y159843
Y154331
Y150000
Y145670
Y140158
Y135827
Y131496
Y125985
Y121654
X527953
Y125985
X520866Y126378
Y130709
X527953Y131496
Y135827
X520866Y136221
X527953Y140158
X520866Y140551
Y144882
X527953Y145670
Y150000
X520866Y150394
X527953Y154331
X520866Y154725
Y159055
X527953Y159843
Y164173
X520866Y164567
X527953Y168504
X520866Y168898
Y173229
X527953Y174016
X520866Y178740
Y183071
X535039
Y178740
Y173229
Y168898
Y164567
Y159055
Y154725
Y150394
Y144882
Y140551
Y136221
Y130709
Y126378
X542126Y121654
Y125985
X549212Y126378
Y130709
X542126Y131496
Y135827
X549212Y136221
X542126Y140158
X549212Y140551
Y144882
X542126Y145670
Y150000
X549212Y150394
X542126Y154331
X549212Y154725
Y159055
X542126Y159843
Y164173
X549212Y164567
X542126Y168504
X549212Y168898
Y173229
X542126Y174016
X549212Y178740
Y183071
X556299Y174016
Y168504
Y164173
Y159843
Y154331
Y150000
Y145670
Y140158
Y135827
Y131496
Y125985
Y121654
T06
X36435Y8514
X21435
X16435
X26435
X31435
X8514Y10593
Y15593
Y20593
Y25593
Y30593
Y35593
Y40593
Y45593
Y50593
Y55593
Y60593
Y65593
Y70593
Y75593
Y80593
Y85593
Y90593
Y95593
Y100593
Y105593
Y110593
Y115593
Y120593
Y125593
Y130593
Y135593
Y140593
Y145593
Y150593
Y155593
Y160593
Y165593
Y170593
Y175593
Y180593
Y185593
Y190593
Y195593
Y200593
Y205593
Y210593
Y215593
Y220593
Y225593
Y230593
Y235593
Y240593
Y245593
Y250593
Y255593
Y260593
Y265593
Y270593
Y275593
Y280593
Y285593
Y290593
Y295593
Y300593
Y305593
Y310593
Y315593
Y320593
Y325593
Y330593
Y335593
Y340593
Y345593
Y350593
Y355593
Y360593
Y365593
Y370593
Y375593
Y380593
Y385593
Y390593
Y395593
Y400593
Y405593
Y410593
Y415593
Y420593
Y425593
Y430593
Y435593
Y440593
Y445593
Y450593
Y455593
Y460593
Y465593
Y470593
Y475593
Y480593
Y485593
Y490593
Y495593
Y500593
Y505593
Y510593
Y515593
Y520593
Y525593
Y530593
Y535593
Y540593
Y545593
Y550593
Y555593
Y560593
Y565593
Y570593
Y575593
Y580593
Y585593
Y590593
Y595593
Y600593
Y605593
Y610593
Y615593
Y620593
Y625593
Y630593
Y635593
Y640593
Y645593
Y650593
Y655593
Y660593
Y665593
Y670593
Y675593
Y680593
Y685593
Y690593
Y695593
Y700593
Y705593
Y710593
Y715593
Y720593
X9942Y725256
X12178Y729728
X14414Y734200
X16650Y738672
X18886Y743144
X21122Y747617
X23358Y752089
X76395Y755266
X76549Y680547
Y675547
X76118Y625275
X51435Y8514
X76435
X71435
X56435
X46435
X66435
X61435
X41435
X81435
X86435
X111435
X91435
X106435
X101435
X96435
X111683Y13266
Y18266
Y23266
Y58266
Y63266
Y68266
Y73266
Y78266
Y83266
Y88266
Y93266
Y98266
Y103266
Y108266
Y113266
Y118266
Y148266
Y153266
Y158266
Y163266
Y168266
Y173266
Y178266
Y183266
Y188266
Y193266
Y198266
Y203266
Y208266
Y213266
Y218266
Y223266
Y228266
Y233266
Y238266
Y243266
Y248266
Y253266
Y258266
Y263266
Y268266
Y273266
Y278266
Y283266
Y288266
Y293266
Y298266
Y303266
Y308266
Y313266
Y318266
Y323266
Y328266
Y333266
Y338266
Y343266
Y348266
Y353266
Y358266
Y363266
Y368266
Y373266
Y378266
Y383266
Y388266
Y393266
Y398266
Y403266
Y408266
Y413266
Y418266
X81118Y625275
X103940Y635460
X95200Y667500
X90400
X85600
X99337Y673756
X81549Y675547
X99337Y678756
X81549Y680547
X99337Y683756
X86300Y703200
Y708000
X83125Y719240
Y724040
X113928Y744775
X103928
X98928
X93928
X118928
X108928
X111395Y755266
X106395
X96395
X101395
X116395
X81395
X91395
X86395
X131395
X136395
X156395
X121395
X151395
X146395
X141395
X126395
X123928Y744775
X155400Y717700
X134223Y691027
X122335Y660582
Y655782
X176395Y755266
X191395
X166395
X181395
X196395
X171395
X161395
X186395
X196700Y704985
X191700
X211700
X221700
X206700
X201700
X226700
X216700
X226395Y755266
X201395
X221395
X216395
X211395
X206395
X236395
X231395
X251395
X246395
X261395
X276395
X241395
X266395
X256395
X271395
X249200Y738500
Y733700
Y728700
Y723700
Y718700
X316395Y755266
X296395
X286395
X291395
X306395
X301395
X281395
X311395
X310559Y725973
X305559
X299500Y725400
X305559Y720973
X310559
X315520Y711720
X298700Y674600
X303700
X312400Y653081
X307600
X317200
X305862Y210014
X305882Y195474
X305382Y190174
X296034Y139002
Y134002
Y129002
Y124002
Y119002
Y114002
Y109002
Y104002
Y99002
Y94002
Y89002
Y84002
Y79002
Y74002
Y69002
Y64002
Y59002
Y54002
Y49002
Y44002
Y39002
Y34002
Y29002
Y24002
Y19002
Y14002
Y9002
X315546Y8514
X300546
X310546
X305546
X320546
X325546
X330546
X334782Y184928
X334882Y190478
Y195478
X321182Y197774
X334882Y200478
X321182Y202574
X323492Y214234
X335100Y218378
X335061Y222578
X335000Y610200
Y615400
Y621200
X325600Y640100
X335200
X330400
X322000Y653081
X325120Y711720
X320320
X326395Y755266
X336395
X331395
X321395
X389168Y743572
X391404Y739100
X393640Y734628
X395876Y730156
X398112Y725684
X399754Y716071
Y711071
Y706071
X373073Y201889
X438500Y32500
X435000Y29000
X438500Y25500
X496500Y76600
X506500
X491500
X501500
X491500Y71600
X501500
X496500
X516693Y46345
Y41545
Y36745
Y31945
X521493
Y36745
Y41545
X526530Y43775
X521493Y46345
X556510Y53626
X556710Y64726
X525000Y76300
X543750Y76480
X548550
X525200Y80900
X567700Y28240
X593017Y69796
X588217
Y74596
X576624Y193205
Y198205
Y203205
Y208205
Y213205
Y223205
Y228205
Y233205
Y238205
Y243205
Y248205
Y253205
Y258205
Y263205
Y268205
Y273205
Y278205
Y333205
Y338205
Y343205
Y348205
Y353205
Y358205
Y363205
Y368205
Y373205
Y378205
Y383205
Y388205
Y393205
Y398205
Y403205
Y408205
Y413205
Y418205
Y423205
Y428205
Y433205
Y438205
Y443205
Y448205
Y498205
Y503205
Y508205
Y513205
Y518205
Y523205
Y528205
Y533205
Y538205
Y543205
Y548205
Y553205
Y558205
Y563205
Y568205
Y573205
Y578205
Y583205
Y588205
X578710Y592712
X580946Y597184
X583182Y601656
X585418Y606129
X587654Y610601
X635975Y621407
X626647Y77507
Y72507
Y67507
X621747Y63307
X608847Y34607
X614032Y33307
X653847Y27107
X668847
X658847
X663847
X653601Y46761
X663601
X668601
X658601
X653601Y51761
X668601
X663601
X658601
X649590Y114036
X674900Y483300
X679100
X663500Y484000
Y489000
X674832Y489100
X679832
X663500Y494000
X674832Y494100
X679832
X665975Y621407
X650975
X640975
X660975
X645975
X670975
X655975
X675975
X680975
X705975
X710975
X685975
X695975
X700975
X690975
X715975
X705080Y521247
X688392Y520482
X683392
X693392
X716578Y509762
X694272Y495786
X683100Y485200
X682800Y480700
X692282Y476720
X684399Y471984
Y466984
X689875Y464586
X710065Y455985
X698275Y438305
X700065Y415985
Y405985
Y395985
Y385985
X710065Y375985
Y365985
Y355985
Y345985
Y335985
Y325985
Y315985
Y305985
X719049Y296011
X708307Y295429
X711574Y285985
X698909Y278104
X709625Y275991
X718617Y275736
X700065Y265985
X710065
X700065Y255985
X710065
Y245985
X700065
Y235985
X710065
X696159Y225829
X700065Y155985
X710065
Y145985
Y135985
X700065
X710065Y125985
X700065
X710065Y115985
X700065
X715546Y8514
X710546
X705546
X695546
X700546
X725546
X755546
X750546
X730546
X735546
X740546
X720546
X745546
X750065Y85985
X740065
X730065Y95985
X750065
X740065
X750065Y105985
X740065
X730065
X720065
X730065Y115985
X750065
X720065
X740065
Y125985
X750065
X730065
X720065
X750065Y135985
X730065
X740065
X720065
X750065Y145985
X740065
X730065
X720065
X750065Y155985
X740065
X730065
X720065
X740065Y165985
X750065
X740065Y175985
X750065
X740065Y185985
X750065
Y195985
X740065
Y205985
X750065
X740065Y215985
X750065
X730065
X720237Y223228
X730190Y223549
X740065Y225985
X750065
Y235985
X740065
X730065
X720065
X731766Y246017
X740065Y245985
X721766Y246017
X750065Y245985
Y255985
X720065
X740065
X730065
X759790Y263326
X720065Y265985
X750065
X730065
X740065
X750065Y275985
X730830Y276087
X741608Y277171
X729294Y285987
X741000Y286000
X752500
X721574Y285985
X740065Y295985
X750065
X729486Y296094
X750065Y305985
X740065
X730065
X720065
X730065Y315985
X720065
X750065
X740065
X730065Y325985
X750065
X740065
X720065
X740065Y335985
X720065
X730065
X750065
X740065Y345985
X720065
X750065
X730065
X750065Y355985
X720065
X730065
X740065
Y365985
X720065
X750065
X730065
X720065Y375985
X750065
X730065
X740065
X730065Y385985
X740065
X750065
X730065Y395985
X750065
X740065
X730065Y405985
X750065
X740065
X750065Y415985
X740065
X730065
X750065Y425985
X740065Y435985
X750065
X730065Y445985
X750065
X740065
X730065Y455985
X750065
X720065
X740065
X720065Y465985
X730065
X740065
X750065
X741217Y493664
X736217
X731580Y507734
X736580
X726590Y511659
X721590
X747602Y517850
X752602
X739334Y524156
X758512Y534430
X747107Y536580
X755975Y621407
X720975
X740975
X745975
X750975
X735975
X730975
X725975
X795975
X780975
X760975
X765975
X770975
X775975
X790975
X785975
X794604Y519082
X789604
X784604
X793015Y507785
X783015
X788015
X771658Y494380
X781658
X776658
Y489380
X771658
X781658
X770065Y465985
X760065
X790065
X780065
X790065Y455985
X770065
X780065
X760065
X770065Y445985
X760065
X790065
X780065
X760065Y435985
X770065
X790065
X780065
X790191Y426486
X770065Y425985
X760065
X780065
X760065Y415985
X790065
X780065
X770065
X760065Y405985
X780065
X770065
X790065
Y395985
X760065
X770065
X780065
X760065Y385985
X780065
X770065
X790065Y375985
X760065
X780065
X770065
X780065Y365985
X770065
X790065
X760065
X780065Y355985
X790065
X760065
X770065
X760065Y345985
X790065
X780065
X770065
Y335985
X791500Y336000
X780065Y335985
X760065
Y325985
X770065
X780065
X790065
X770065Y315985
X760065
X780065
X790065
X780065Y305985
X770065
X760065
X790065
X780065Y295985
X770065
X760065
X790065
X760065Y285985
X790065
X780065
X770065
X773469Y277001
X780065Y275985
X763133Y275881
X787817Y275879
X790065Y265985
X780065
X770065
X760065Y255985
X780065
X770065
X790065
X780065Y245985
X790065
X760065
X770065
Y235985
X780065
X760065
X790065
X760065Y225985
X770065
X790065
X780065
X770065Y215985
X780065
X760065
X770065Y205985
X760065
X770065Y195985
X760065
X770065Y185985
X760065
Y175985
X770065
Y165985
X760065
X770065Y155985
X790065
X760065
X780065
X790065Y145985
X770065
X760065
X780065
Y135985
X790065
X770065
X760065
X790065Y125985
X780065
X770065
X760065
X790065Y115985
X780065
X770065
X760065
X770065Y105985
X760065
X790065
X780065
Y95985
X760065
X770065
X760065Y85985
X770065
Y75985
Y65985
Y55985
X775546Y8514
X760546
X790546
X785546
X770546
X765546
X795546
X780546
X825546
X830546
X810546
X805546
X835546
X815546
X820546
X800546
X820065Y105985
Y115985
X810065
X800065
X820065Y125985
X800065
X810065
X800065Y135985
X810065
X820065
X810065Y145985
X820065
X800065
X820065Y155985
X800065
X810065
X820065Y225985
X810065Y235985
X820065
X800065
Y245985
X820065
X810065
Y255985
X800065
X820065
Y265985
X800065
X810065
X800065Y275985
X810065
X820313Y276188
X810065Y285985
X800065
X820065
X810065Y295985
X820065
X800065
X810065Y305985
X800065
X820065
X810000Y314000
X800065Y315985
Y325985
X810065
X800065Y335985
Y345985
Y355985
Y365985
Y375985
X809000Y429400
X800065Y455985
Y465985
X835057Y494320
X820161Y507954
X815161
X825161
X836023Y508124
X805983Y508293
X805771Y518743
X830975Y621407
X835975
X825975
X800975
X820975
X805975
X815975
X810975
X854971Y712313
Y707313
Y702313
Y697313
Y692313
Y687313
Y682313
Y677313
Y672313
Y667313
Y662313
Y657313
Y652313
Y647313
Y642313
Y637313
X840975Y621407
X840057Y494320
X876451Y407949
X859407Y309914
X864207
Y305114
X859407
X864207Y300314
X859407
X864207Y295314
X859407
X864207Y290314
X859407
X864207Y285314
X859407
X857965Y273150
X873376Y271313
X868376
X875122Y216781
X875222Y211781
Y206781
X853436Y113717
Y108917
X853435Y95060
Y90260
X845546Y8514
X850546
X840546
X900546
X910546
X905546
X915546
X916683Y17377
Y22377
Y27377
Y32377
Y37377
Y42377
Y47377
Y52377
Y57377
X897622Y59214
X892822
X883222
X888022
X916683Y62377
X885722Y63714
X900122
X890522
X895322
X880922
X916683Y67377
Y72377
Y77377
X902050Y81510
X897250
X916683Y82377
X902050Y86310
X897250
X916683Y87377
X897250Y91110
X902050
X916683Y92377
X902050Y95910
X897250
X916683Y97377
Y102377
Y107377
Y112377
Y117377
Y122377
Y127377
Y132377
Y137377
Y142377
Y147377
Y152377
Y157377
Y162377
Y167377
Y172377
Y177377
Y182377
Y187377
Y192377
Y197377
X900600Y201239
X916683Y202377
X880222Y206781
X916683Y207377
X902803Y207684
X897803
X880222Y211781
X916683Y212377
X897803Y212684
X902803
X880122Y216781
X916683Y217377
X897803Y217684
X902803
X916683Y222377
X891031Y223468
X896031
X916683Y227377
X896031Y228468
X891031
X916683Y232377
X891031Y233468
X896031
X916683Y237377
X896031Y238468
X891031
X916683Y242377
Y247377
Y252377
Y257377
Y262377
Y267377
X897195Y270688
X902195
X916683Y272377
X902195Y275688
X897195
X916683Y277377
Y282377
Y287377
X895995Y290712
X900995
X916683Y292377
X901030Y296330
X896030
X916683Y297377
Y302377
Y307377
X895716Y311058
X900716
X916683Y312377
X895819Y316367
X900819
X916683Y317377
Y322377
Y327377
Y332377
Y337377
Y342377
Y347377
Y352377
Y357377
Y362377
Y367377
X897091Y369397
X902091
X916683Y372377
X902091Y374397
X897091
X916683Y377377
X902091Y379397
X897091
X916683Y382377
Y387377
X883548Y387923
X893548
X888548
X916683Y392377
X888548Y392923
X883548
X893548
X916683Y397377
Y402377
Y407377
X890665Y410841
X885665
X880665
X900665
X895665
X916683Y412377
Y417377
Y422377
Y427377
Y432377
Y437377
Y442377
Y447377
Y452377
Y457377
Y462377
Y467377
Y472377
Y477377
Y482377
Y487377
Y492377
Y497377
Y502377
Y507377
Y512377
Y517377
Y522377
Y527377
Y532377
Y537377
Y542377
Y547377
Y552377
Y557377
Y562377
Y567377
Y572377
Y577377
Y582377
Y587377
Y592377
Y597377
Y602377
Y607377
Y612377
Y617377
Y622377
Y627377
Y632377
Y637377
Y642377
Y647377
Y652377
Y657377
Y662377
Y667377
Y672377
Y677377
Y682377
Y687377
Y692377
Y697377
Y702377
Y707377
Y712377
Y717377
Y722377
X914457Y726851
X912221Y731323
X909985Y735796
X907749Y740268
X905513Y744740
X903277Y749212
X901041Y753684
T07
X346457Y57007
X353543Y55039
Y62913
X346457Y66850
X353543Y70787
Y78661
X346457Y74724
Y84567
X353543Y86535
T08
X801024Y24409
X811024
X821024
T09
X33464Y34449
X38386Y24606
X56102
X61024Y34449
X80708Y44292
X85630Y34449
X103346
X108268Y44292
T10
X70865Y98425
Y472441
X364173Y740157
X314960Y472441
X405511Y39370
X587795Y307087
X590551Y472441
X612204Y606299
X875984Y472441
Y606299
Y740157
T11
X875984Y31496
X49212Y740157
T12
X163189Y669291
T13
X201801Y684252
X225601
T14
X305906Y388386
T15
X666929Y510236
X765354
T16
X305906Y182874
T17
X745669Y510236
X844094
T18
X34652Y111485
X33297Y703990
X148206Y21054
X261147Y405580
X486498Y356293
X807831Y734367
X899219Y47960
T19
X488838Y164744
T20
X488838Y137225
T21
X309055Y157677
X90157Y413582
M30
